# TIMECARD (Time Appliance Project (Time Card)) — schematic netlist excerpt (pin names and nets, part order shuffled) for the footprints in the layout excerpt that follows; sources: Cadence DE-HDL packaged netlist, KiCad conversion of R4006-B0001-02_R01.brd

C119  CAPACITOR  0.1UF 10V 10%  pkg SMC_0402R_H022  page 14 : \1\ = XP3R3V_FPGA ; \2\ = SG
C91  CAPACITOR  4.7UF 6.3V 20%  pkg SMC_0402R_H026  page 24 : \1\ = XP3R3V_FT4232 ; \2\ = SG

(kicad_pcb
	(version 20260206)
	(generator "pcbnew")
	(generator_version "10.0")
	(general
		(thickness 1.6)
		(legacy_teardrops no)
	)
	(paper "A4")
	(title_block
		(title "timecard-production-celestica-r4006 — R4006-B0001-02_R01.brd")
		(comment 1 "Time Appliance Project (Time Card) / footprints 1087-1088 of 1113")
	)
	(layers
		(0 "F.Cu" signal "TOP")
		(4 "In1.Cu" signal "L02_GND1")
		(6 "In2.Cu" signal "L03_SIG1")
		(8 "In3.Cu" signal "L04_GND2")
		(10 "In4.Cu" signal "L05_VCC1")
		(12 "In5.Cu" signal "L06_VCC2")
		(14 "In6.Cu" signal "L07_GND3")
		(16 "In7.Cu" signal "L08_SIG2")
		(18 "In8.Cu" signal "L09_GND4")
		(2 "B.Cu" signal "BOTTOM")
		(9 "F.Adhes" user "F.Adhesive")
		(11 "B.Adhes" user "B.Adhesive")
		(13 "F.Paste" user "Package Geometry/Pastemask Top")
		(15 "B.Paste" user "Package Geometry/Pastemask Bottom")
		(5 "F.SilkS" user "Ref Des/Silkscreen Top")
		(7 "B.SilkS" user "Ref Des/Silkscreen Bottom")
		(1 "F.Mask" user "Board Geometry/Soldermask Top")
		(3 "B.Mask" user "Board Geometry/Soldermask Bottom")
		(17 "Dwgs.User" user "User.Drawings")
		(19 "Cmts.User" user "User.Comments")
		(21 "Eco1.User" user "User.Eco1")
		(23 "Eco2.User" user "User.Eco2")
		(25 "Edge.Cuts" user "Board Geometry/Outline")
		(27 "Margin" user)
		(31 "F.CrtYd" user "Package Geometry/Place Bound Top")
		(29 "B.CrtYd" user "Package Geometry/Place Bound Bottom")
		(35 "F.Fab" user "Ref Des/Assembly Top")
		(33 "B.Fab" user "Ref Des/Assembly Bottom")
	)
	(footprint ""
		(layer "B.Cu")
		(at 34.925 -90.932 90)
		(property "Reference" "C91"
			(at 3.048 -0.29337 270)
			(unlocked yes)
			(layer "B.SilkS")
			(effects
				(font
					(size 0.7874 0.5842)
					(thickness 0.1524)
				)
				(justify mirror)
			)
		)
		(property "Value" "VAL*"
			(at -0.02032 2.13233 90)
			(unlocked yes)
			(layer "B.Fab")
			(hide yes)
			(effects
				(font
					(size 0.7874 0.5842)
					(thickness 0.1524)
				)
				(justify mirror)
			)
		)
		(property "Tolerance" "TOL*"
			(at -0.044704 3.05435 90)
			(unlocked yes)
			(layer "Cmts.User")
			(hide yes)
			(effects
				(font
					(size 0.7874 0.5842)
					(thickness 0.1524)
				)
				(justify mirror)
			)
		)
		(property "User Part Number" "PARTNUM*"
			(at -0.02032 4.024884 90)
			(unlocked yes)
			(layer "Cmts.User")
			(hide yes)
			(effects
				(font
					(size 0.7874 0.5842)
					(thickness 0.1524)
				)
				(justify mirror)
			)
		)
		(property "Device Type" "CAPACITOR-G105-0F475-BM,4.7UF,A"
			(at -0.008382 1.210564 90)
			(unlocked yes)
			(layer "B.Fab")
			(hide yes)
			(effects
				(font
					(size 0.7874 0.5842)
					(thickness 0.1524)
				)
				(justify mirror)
			)
		)
		(duplicate_pad_numbers_are_jumpers no)
		(fp_line
			(start 1.143 -0.5588)
			(end 1.143 0.5588)
			(stroke
				(width 0.1)
				(type default)
			)
			(layer "B.SilkS")
		)
		(fp_line
			(start -1.143 -0.5588)
			(end 1.143 -0.5588)
			(stroke
				(width 0.1)
				(type default)
			)
			(layer "B.SilkS")
		)
		(fp_line
			(start 1.143 0.5588)
			(end -1.143 0.5588)
			(stroke
				(width 0.1)
				(type default)
			)
			(layer "B.SilkS")
		)
		(fp_line
			(start -1.143 0.5588)
			(end -1.143 -0.5588)
			(stroke
				(width 0.1)
				(type default)
			)
			(layer "B.SilkS")
		)
		(fp_poly
			(pts
				(xy 1.143 0.5588) (xy -1.143 0.5588) (xy -1.143 -0.5588) (xy 1.143 -0.5588)
			)
			(stroke
				(width 0)
				(type default)
			)
			(fill no)
			(layer "B.CrtYd")
		)
		(fp_line
			(start 0.508 -0.3048)
			(end 0.508 0.3048)
			(stroke
				(width 0.1)
				(type default)
			)
			(layer "B.Fab")
		)
		(fp_line
			(start -0.508 -0.3048)
			(end 0.508 -0.3048)
			(stroke
				(width 0.1)
				(type default)
			)
			(layer "B.Fab")
		)
		(fp_line
			(start 0.508 0.3048)
			(end -0.508 0.3048)
			(stroke
				(width 0.1)
				(type default)
			)
			(layer "B.Fab")
		)
		(fp_line
			(start -0.508 0.3048)
			(end -0.508 -0.3048)
			(stroke
				(width 0.1)
				(type default)
			)
			(layer "B.Fab")
		)
		(pad "1" smd rect
			(at 0.5334 0 270)
			(size 0.7112 0.6096)
			(layers "B.Cu" "B.Mask" "B.Paste")
			(net "XP3R3V_FT4232")
		)
		(pad "2" smd rect
			(at -0.5334 0 270)
			(size 0.7112 0.6096)
			(layers "B.Cu" "B.Mask" "B.Paste")
			(net "SG")
		)
		(zone
			(layer "B.Cu")
			(hatch none 0.5)
			(connect_pads
				(clearance 0)
			)
			(min_thickness 0.25)
			(keepout
				(tracks allowed)
				(vias not_allowed)
				(pads allowed)
				(copperpour not_allowed)
				(footprints allowed)
			)
			(placement
				(enabled no)
				(sheetname "")
			)
			(fill
				(thermal_gap 0.5)
				(thermal_bridge_width 0.5)
				(island_removal_mode 0)
			)
			(polygon
				(pts
					(xy 35.2298 -91.0082) (xy 34.6202 -91.0082) (xy 34.6202 -90.8558) (xy 35.2298 -90.8558)
				)
			)
		)
		(zone
			(layer "B.Cu")
			(hatch none 0.5)
			(connect_pads
				(clearance 0)
			)
			(min_thickness 0.25)
			(keepout
				(tracks not_allowed)
				(vias allowed)
				(pads allowed)
				(copperpour not_allowed)
				(footprints allowed)
			)
			(placement
				(enabled no)
				(sheetname "")
			)
			(fill
				(thermal_gap 0.5)
				(thermal_bridge_width 0.5)
				(island_removal_mode 0)
			)
			(polygon
				(pts
					(xy 35.2298 -91.0082) (xy 34.6202 -91.0082) (xy 34.6202 -90.8558) (xy 35.2298 -90.8558)
				)
			)
		)
	)
	(footprint ""
		(layer "B.Cu")
		(at 105.847134 -50.323242 -90)
		(property "Reference" "C119"
			(at 0.412242 -0.928116 270)
			(unlocked yes)
			(layer "B.SilkS")
			(effects
				(font
					(size 0.635 0.4064)
					(thickness 0.1524)
				)
				(justify mirror)
			)
		)
		(property "Value" "VAL*"
			(at 0 3.718306 270)
			(unlocked yes)
			(layer "B.Fab")
			(hide yes)
			(effects
				(font
					(size 0.7874 0.5842)
					(thickness 0.127)
				)
				(justify mirror)
			)
		)
		(property "Device Type" "CAPACITOR-G105-0B104-CK,0.1UF,A"
			(at 0 1.432306 270)
			(unlocked yes)
			(layer "B.Fab")
			(hide yes)
			(effects
				(font
					(size 0.7874 0.5842)
					(thickness 0.127)
				)
				(justify mirror)
			)
		)
		(property "User Part Number" "PARTNUM*"
			(at 0 2.575306 270)
			(unlocked yes)
			(layer "Cmts.User")
			(hide yes)
			(effects
				(font
					(size 0.7874 0.5842)
					(thickness 0.127)
				)
				(justify mirror)
			)
		)
		(property "Tolerance" "TOL*"
			(at 0 4.861306 270)
			(unlocked yes)
			(layer "Cmts.User")
			(hide yes)
			(effects
				(font
					(size 0.7874 0.5842)
					(thickness 0.127)
				)
				(justify mirror)
			)
		)
		(duplicate_pad_numbers_are_jumpers no)
		(fp_line
			(start -0.970026 0.4699)
			(end 0.970026 0.4699)
			(stroke
				(width 0.1)
				(type default)
			)
			(layer "B.SilkS")
		)
		(fp_line
			(start 0.970026 0.4699)
			(end 0.970026 -0.4699)
			(stroke
				(width 0.1)
				(type default)
			)
			(layer "B.SilkS")
		)
		(fp_line
			(start -0.970026 -0.4699)
			(end -0.970026 0.4699)
			(stroke
				(width 0.1)
				(type default)
			)
			(layer "B.SilkS")
		)
		(fp_line
			(start 0.970026 -0.4699)
			(end -0.970026 -0.4699)
			(stroke
				(width 0.1)
				(type default)
			)
			(layer "B.SilkS")
		)
		(fp_poly
			(pts
				(xy 0.970026 0.4699) (xy -0.970026 0.4699) (xy -0.970026 -0.4699) (xy 0.970026 -0.4699)
			)
			(stroke
				(width 0)
				(type default)
			)
			(fill no)
			(layer "B.CrtYd")
		)
		(fp_line
			(start -0.508 0.3048)
			(end 0.508 0.3048)
			(stroke
				(width 0.1)
				(type default)
			)
			(layer "B.Fab")
		)
		(fp_line
			(start 0.508 0.3048)
			(end 0.508 -0.3048)
			(stroke
				(width 0.1)
				(type default)
			)
			(layer "B.Fab")
		)
		(fp_line
			(start -0.508 -0.3048)
			(end -0.508 0.3048)
			(stroke
				(width 0.1)
				(type default)
			)
			(layer "B.Fab")
		)
		(fp_line
			(start 0.508 -0.3048)
			(end -0.508 -0.3048)
			(stroke
				(width 0.1)
				(type default)
			)
			(layer "B.Fab")
		)
		(pad "1" smd circle
			(at 0.500126 0 90)
			(size 0.635 0.635)
			(layers "B.Cu" "B.Mask" "B.Paste")
			(net "XP3R3V_FPGA")
		)
		(pad "2" smd circle
			(at -0.500126 0 90)
			(size 0.635 0.635)
			(layers "B.Cu" "B.Mask" "B.Paste")
			(net "SG")
		)
	)
)
